(kicad_pcb
	(version 20260206)
	(generator "pcbnew")
	(generator_version "10.0")
	(general
		(thickness 1.6)
		(legacy_teardrops no)
	)
	(paper "A4")
	(title_block
		(title "Wiwynn_Tioga_Pass_MB.brd")
		(comment 1 "Tioga Pass / footprints 868-874 of 4770")
	)
	(layers
		(0 "F.Cu" signal "TOP")
		(4 "In1.Cu" signal "L2GND")
		(6 "In2.Cu" signal "L3")
		(8 "In3.Cu" signal "L4GND")
		(10 "In4.Cu" signal "L5")
		(12 "In5.Cu" signal "L6GND")
		(14 "In6.Cu" signal "L7VCC")
		(16 "In7.Cu" signal "L8VCC")
		(18 "In8.Cu" signal "L9GND")
		(20 "In9.Cu" signal "L10")
		(22 "In10.Cu" signal "L11GND")
		(24 "In11.Cu" signal "L12")
		(26 "In12.Cu" signal "L13GND")
		(2 "B.Cu" signal "BOTTOM")
		(9 "F.Adhes" user "F.Adhesive")
		(11 "B.Adhes" user "B.Adhesive")
		(13 "F.Paste" user "Package Geometry/Pastemask Top")
		(15 "B.Paste" user "Package Geometry/Pastemask Bottom")
		(5 "F.SilkS" user "Ref Des/Silkscreen Top")
		(7 "B.SilkS" user "Ref Des/Silkscreen Bottom")
		(1 "F.Mask" user "Board Geometry/Soldermask Top")
		(3 "B.Mask" user "Board Geometry/Soldermask Bottom")
		(17 "Dwgs.User" user "User.Drawings")
		(19 "Cmts.User" user "User.Comments")
		(21 "Eco1.User" user "User.Eco1")
		(23 "Eco2.User" user "User.Eco2")
		(25 "Edge.Cuts" user "Board Geometry/Outline")
		(27 "Margin" user)
		(31 "F.CrtYd" user "Package Geometry/Place Bound Top")
		(29 "B.CrtYd" user "Package Geometry/Place Bound Bottom")
		(35 "F.Fab" user "Ref Des/Assembly Top")
		(33 "B.Fab" user "Ref Des/Assembly Bottom")
	)
	(footprint ""
		(layer "F.Cu")
		(at 404.241 -82.7405 180)
		(property "Reference" "R2P15"
			(at 0 0 180)
			(layer "F.SilkS")
			(hide yes)
			(effects
				(font
					(size 1.27 1.27)
				)
			)
		)
		(property "Value" ""
			(at 0 0 180)
			(layer "F.Fab")
			(effects
				(font
					(size 1.27 1.27)
				)
			)
		)
		(duplicate_pad_numbers_are_jumpers no)
		(fp_poly
			(pts
				(xy -0.2794 -0.1016) (xy 0.2794 -0.1016) (xy 0.2794 0.9906) (xy -0.2794 0.9906)
			)
			(stroke
				(width 0)
				(type default)
			)
			(fill no)
			(layer "F.CrtYd")
		)
		(fp_line
			(start 0.2794 0.9906)
			(end 0.2794 -0.1016)
			(stroke
				(width 0.1)
				(type default)
			)
			(layer "F.Fab")
		)
		(fp_line
			(start 0.2794 -0.1016)
			(end -0.2794 -0.1016)
			(stroke
				(width 0.1)
				(type default)
			)
			(layer "F.Fab")
		)
		(fp_line
			(start -0.2794 0.9906)
			(end 0.2794 0.9906)
			(stroke
				(width 0.1)
				(type default)
			)
			(layer "F.Fab")
		)
		(fp_line
			(start -0.2794 -0.1016)
			(end -0.2794 0.9906)
			(stroke
				(width 0.1)
				(type default)
			)
			(layer "F.Fab")
		)
		(pad "1" smd rect
			(at 0 0 180)
			(size 0.508 0.508)
			(layers "F.Cu" "F.Mask" "F.Paste")
			(net "P3V3")
		)
		(pad "2" smd rect
			(at 0 0.889 180)
			(size 0.508 0.508)
			(layers "F.Cu" "F.Mask" "F.Paste")
			(net "FM_M2_SSD_PEDET")
		)
		(zone
			(layer "F.Cu")
			(hatch none 0.5)
			(connect_pads
				(clearance 0)
			)
			(min_thickness 0.25)
			(keepout
				(tracks not_allowed)
				(vias allowed)
				(pads allowed)
				(copperpour not_allowed)
				(footprints allowed)
			)
			(placement
				(enabled no)
				(sheetname "")
			)
			(fill
				(thermal_gap 0.5)
				(thermal_bridge_width 0.5)
				(island_removal_mode 0)
			)
			(polygon
				(pts
					(xy 404.495 -83.3755) (xy 403.987 -83.3755) (xy 403.987 -82.9945) (xy 404.495 -82.9945)
				)
			)
		)
		(zone
			(layer "F.Cu")
			(hatch none 0.5)
			(connect_pads
				(clearance 0)
			)
			(min_thickness 0.25)
			(keepout
				(tracks allowed)
				(vias not_allowed)
				(pads allowed)
				(copperpour not_allowed)
				(footprints allowed)
			)
			(placement
				(enabled no)
				(sheetname "")
			)
			(fill
				(thermal_gap 0.5)
				(thermal_bridge_width 0.5)
				(island_removal_mode 0)
			)
			(polygon
				(pts
					(xy 404.495 -82.9945) (xy 403.987 -82.9945) (xy 403.987 -83.3755) (xy 404.495 -83.3755)
				)
			)
		)
	)
	(footprint ""
		(layer "F.Cu")
		(at 309.18785 -32.492696 90)
		(property "Reference" "Q1F1"
			(at -0.229362 -1.2065 90)
			(unlocked yes)
			(layer "F.SilkS")
			(effects
				(font
					(size 0.4064 0.254)
					(thickness 0.1524)
				)
				(justify left)
			)
		)
		(property "Value" ""
			(at 0 0 90)
			(layer "F.Fab")
			(effects
				(font
					(size 1.27 1.27)
				)
			)
		)
		(duplicate_pad_numbers_are_jumpers no)
		(fp_line
			(start 1.778 -0.5715)
			(end 1.778 0.3175)
			(stroke
				(width 0.1524)
				(type default)
			)
			(layer "F.SilkS")
		)
		(fp_line
			(start 0.9525 -0.5715)
			(end 1.778 -0.5715)
			(stroke
				(width 0.1524)
				(type default)
			)
			(layer "F.SilkS")
		)
		(fp_line
			(start 0.381 0.635)
			(end 0.381 1.27)
			(stroke
				(width 0.1524)
				(type default)
			)
			(layer "F.SilkS")
		)
		(fp_line
			(start 1.778 2.4765)
			(end 1.778 1.5875)
			(stroke
				(width 0.1524)
				(type default)
			)
			(layer "F.SilkS")
		)
		(fp_line
			(start 0.9525 2.4765)
			(end 1.778 2.4765)
			(stroke
				(width 0.1524)
				(type default)
			)
			(layer "F.SilkS")
		)
		(fp_circle
			(center -0.9525 -0.9271)
			(end -0.9525 -0.8001)
			(stroke
				(width 0.254)
				(type default)
			)
			(fill no)
			(layer "F.SilkS")
		)
		(fp_poly
			(pts
				(xy 1.778 2.4765) (xy 0.381 2.4765) (xy 0.381 -0.5715) (xy 1.778 -0.5715)
			)
			(stroke
				(width 0)
				(type default)
			)
			(fill no)
			(layer "F.CrtYd")
		)
		(fp_line
			(start 1.778 -0.5715)
			(end 0.381 -0.5715)
			(stroke
				(width 0.1)
				(type default)
			)
			(layer "F.Fab")
		)
		(fp_line
			(start 0.381 -0.5715)
			(end 0.381 2.4765)
			(stroke
				(width 0.1)
				(type default)
			)
			(layer "F.Fab")
		)
		(fp_line
			(start 1.778 2.4765)
			(end 1.778 -0.5715)
			(stroke
				(width 0.1)
				(type default)
			)
			(layer "F.Fab")
		)
		(fp_line
			(start 0.381 2.4765)
			(end 1.778 2.4765)
			(stroke
				(width 0.1)
				(type default)
			)
			(layer "F.Fab")
		)
		(fp_circle
			(center -0.9525 -0.9271)
			(end -0.9525 -0.8001)
			(stroke
				(width 0.254)
				(type default)
			)
			(fill no)
			(layer "F.Fab")
		)
		(pad "1" smd rect
			(at 0 0 90)
			(size 1.143 0.508)
			(layers "F.Cu" "F.Mask" "F.Paste")
			(net "FM_ADR_COMPLETE_CPU0_R")
		)
		(pad "2" smd rect
			(at 0 1.905 90)
			(size 1.143 0.508)
			(layers "F.Cu" "F.Mask" "F.Paste")
			(net "GND")
		)
		(pad "3" smd rect
			(at 2.159 0.9525 90)
			(size 1.143 0.508)
			(layers "F.Cu" "F.Mask" "F.Paste")
			(net "IRQ_DIMM_SAVE_N")
		)
	)
	(footprint ""
		(layer "F.Cu")
		(at 414.962594 -48.083216 180)
		(property "Reference" "C25W20"
			(at -0.8382 -0.67818 180)
			(unlocked yes)
			(layer "F.SilkS")
			(effects
				(font
					(size 0.4064 0.254)
					(thickness 0.1524)
				)
				(justify left)
			)
		)
		(property "Value" ""
			(at 0 0 180)
			(layer "F.Fab")
			(effects
				(font
					(size 1.27 1.27)
				)
			)
		)
		(duplicate_pad_numbers_are_jumpers no)
		(fp_poly
			(pts
				(xy 0.3048 -0.1016) (xy 0.3048 0.9906) (xy -0.3048 0.9906) (xy -0.3048 -0.1016)
			)
			(stroke
				(width 0)
				(type default)
			)
			(fill no)
			(layer "F.CrtYd")
		)
		(fp_line
			(start 0.3048 0.9906)
			(end 0.3048 -0.1016)
			(stroke
				(width 0.1)
				(type default)
			)
			(layer "F.Fab")
		)
		(fp_line
			(start 0.3048 -0.1016)
			(end -0.3048 -0.1016)
			(stroke
				(width 0.1)
				(type default)
			)
			(layer "F.Fab")
		)
		(fp_line
			(start -0.3048 0.9906)
			(end 0.3048 0.9906)
			(stroke
				(width 0.1)
				(type default)
			)
			(layer "F.Fab")
		)
		(fp_line
			(start -0.3048 -0.1016)
			(end -0.3048 0.9906)
			(stroke
				(width 0.1)
				(type default)
			)
			(layer "F.Fab")
		)
		(pad "1" smd rect
			(at 0 0 180)
			(size 0.508 0.508)
			(layers "F.Cu" "F.Mask" "F.Paste")
			(net "P2E_SSB_BMC_RX_DP")
		)
		(pad "2" smd rect
			(at 0 0.889 180)
			(size 0.508 0.508)
			(layers "F.Cu" "F.Mask" "F.Paste")
			(net "P2E_SSB_BMC_RX_C_DP")
		)
		(zone
			(layer "F.Cu")
			(hatch none 0.5)
			(connect_pads
				(clearance 0)
			)
			(min_thickness 0.25)
			(keepout
				(tracks not_allowed)
				(vias allowed)
				(pads allowed)
				(copperpour not_allowed)
				(footprints allowed)
			)
			(placement
				(enabled no)
				(sheetname "")
			)
			(fill
				(thermal_gap 0.5)
				(thermal_bridge_width 0.5)
				(island_removal_mode 0)
			)
			(polygon
				(pts
					(xy 415.216594 -48.718216) (xy 414.708594 -48.718216) (xy 414.708594 -48.337216) (xy 415.216594 -48.337216)
				)
			)
		)
		(zone
			(layer "F.Cu")
			(hatch none 0.5)
			(connect_pads
				(clearance 0)
			)
			(min_thickness 0.25)
			(keepout
				(tracks allowed)
				(vias not_allowed)
				(pads allowed)
				(copperpour not_allowed)
				(footprints allowed)
			)
			(placement
				(enabled no)
				(sheetname "")
			)
			(fill
				(thermal_gap 0.5)
				(thermal_bridge_width 0.5)
				(island_removal_mode 0)
			)
			(polygon
				(pts
					(xy 415.216594 -48.337216) (xy 414.708594 -48.337216) (xy 414.708594 -48.718216) (xy 415.216594 -48.718216)
				)
			)
		)
	)
	(footprint ""
		(layer "F.Cu")
		(at 116.332 -75.565 90)
		(property "Reference" "R3D13"
			(at 0 0 90)
			(layer "F.SilkS")
			(hide yes)
			(effects
				(font
					(size 1.27 1.27)
				)
			)
		)
		(property "Value" ""
			(at 0 0 90)
			(layer "F.Fab")
			(effects
				(font
					(size 1.27 1.27)
				)
			)
		)
		(duplicate_pad_numbers_are_jumpers no)
		(fp_poly
			(pts
				(xy -0.2794 -0.1016) (xy 0.2794 -0.1016) (xy 0.2794 0.9906) (xy -0.2794 0.9906)
			)
			(stroke
				(width 0)
				(type default)
			)
			(fill no)
			(layer "F.CrtYd")
		)
		(fp_line
			(start 0.2794 -0.1016)
			(end -0.2794 -0.1016)
			(stroke
				(width 0.1)
				(type default)
			)
			(layer "F.Fab")
		)
		(fp_line
			(start -0.2794 -0.1016)
			(end -0.2794 0.9906)
			(stroke
				(width 0.1)
				(type default)
			)
			(layer "F.Fab")
		)
		(fp_line
			(start 0.2794 0.9906)
			(end 0.2794 -0.1016)
			(stroke
				(width 0.1)
				(type default)
			)
			(layer "F.Fab")
		)
		(fp_line
			(start -0.2794 0.9906)
			(end 0.2794 0.9906)
			(stroke
				(width 0.1)
				(type default)
			)
			(layer "F.Fab")
		)
		(pad "1" smd rect
			(at 0 0 90)
			(size 0.508 0.508)
			(layers "F.Cu" "F.Mask" "F.Paste")
			(net "GND")
		)
		(pad "2" smd rect
			(at 0 0.889 90)
			(size 0.508 0.508)
			(layers "F.Cu" "F.Mask" "F.Paste")
			(net "PD_CPU1_BIST_ENABLE")
		)
		(zone
			(layer "F.Cu")
			(hatch none 0.5)
			(connect_pads
				(clearance 0)
			)
			(min_thickness 0.25)
			(keepout
				(tracks allowed)
				(vias not_allowed)
				(pads allowed)
				(copperpour not_allowed)
				(footprints allowed)
			)
			(placement
				(enabled no)
				(sheetname "")
			)
			(fill
				(thermal_gap 0.5)
				(thermal_bridge_width 0.5)
				(island_removal_mode 0)
			)
			(polygon
				(pts
					(xy 116.586 -75.311) (xy 116.586 -75.819) (xy 116.967 -75.819) (xy 116.967 -75.311)
				)
			)
		)
		(zone
			(layer "F.Cu")
			(hatch none 0.5)
			(connect_pads
				(clearance 0)
			)
			(min_thickness 0.25)
			(keepout
				(tracks not_allowed)
				(vias allowed)
				(pads allowed)
				(copperpour not_allowed)
				(footprints allowed)
			)
			(placement
				(enabled no)
				(sheetname "")
			)
			(fill
				(thermal_gap 0.5)
				(thermal_bridge_width 0.5)
				(island_removal_mode 0)
			)
			(polygon
				(pts
					(xy 116.967 -75.311) (xy 116.967 -75.819) (xy 116.586 -75.819) (xy 116.586 -75.311)
				)
			)
		)
	)
	(footprint ""
		(layer "F.Cu")
		(at 454.914 -29.337)
		(property "Reference" "DS9F1"
			(at 0.29083 4.3307 90)
			(unlocked yes)
			(layer "F.SilkS")
			(effects
				(font
					(size 0.7874 0.5842)
					(thickness 0.1524)
				)
			)
		)
		(property "Value" ""
			(at 0 0 0)
			(layer "F.Fab")
			(effects
				(font
					(size 1.27 1.27)
				)
			)
		)
		(duplicate_pad_numbers_are_jumpers no)
		(fp_line
			(start -1.46558 0.060452)
			(end -0.984758 0.060452)
			(stroke
				(width 0.1524)
				(type default)
			)
			(layer "F.SilkS")
		)
		(fp_line
			(start -1.46558 0.893318)
			(end -0.503936 0.893318)
			(stroke
				(width 0.1524)
				(type default)
			)
			(layer "F.SilkS")
		)
		(fp_line
			(start -0.984758 -0.851154)
			(end -0.984758 0.060452)
			(stroke
				(width 0.1524)
				(type default)
			)
			(layer "F.SilkS")
		)
		(fp_line
			(start -0.984758 0.060452)
			(end -0.503936 0.060452)
			(stroke
				(width 0.1524)
				(type default)
			)
			(layer "F.SilkS")
		)
		(fp_line
			(start -0.984758 0.893318)
			(end -1.46558 0.060452)
			(stroke
				(width 0.1524)
				(type default)
			)
			(layer "F.SilkS")
		)
		(fp_line
			(start -0.984758 2.01676)
			(end -0.984758 0.893318)
			(stroke
				(width 0.1524)
				(type default)
			)
			(layer "F.SilkS")
		)
		(fp_line
			(start -0.503936 0.060452)
			(end -0.984758 0.893318)
			(stroke
				(width 0.1524)
				(type default)
			)
			(layer "F.SilkS")
		)
		(fp_rect
			(start -0.4064 1.6891)
			(end 0.4064 0.0889)
			(stroke
				(width 0)
				(type default)
			)
			(fill no)
			(layer "F.CrtYd")
		)
		(fp_line
			(start -1.554734 0.007112)
			(end -0.59309 0.007112)
			(stroke
				(width 0.1)
				(type default)
			)
			(layer "F.Fab")
		)
		(fp_line
			(start -1.554734 0.839978)
			(end -0.59309 0.839978)
			(stroke
				(width 0.1)
				(type default)
			)
			(layer "F.Fab")
		)
		(fp_line
			(start -1.073912 0.007112)
			(end -1.073912 -0.904494)
			(stroke
				(width 0.1)
				(type default)
			)
			(layer "F.Fab")
		)
		(fp_line
			(start -1.073912 0.839978)
			(end -1.554734 0.007112)
			(stroke
				(width 0.1)
				(type default)
			)
			(layer "F.Fab")
		)
		(fp_line
			(start -1.073912 0.839978)
			(end -1.073912 1.96342)
			(stroke
				(width 0.1)
				(type default)
			)
			(layer "F.Fab")
		)
		(fp_line
			(start -0.59309 0.007112)
			(end -1.073912 0.839978)
			(stroke
				(width 0.1)
				(type default)
			)
			(layer "F.Fab")
		)
		(fp_line
			(start -0.4064 0.0889)
			(end 0.4064 0.0889)
			(stroke
				(width 0.1)
				(type default)
			)
			(layer "F.Fab")
		)
		(fp_line
			(start -0.4064 1.6891)
			(end -0.4064 0.0889)
			(stroke
				(width 0.1)
				(type default)
			)
			(layer "F.Fab")
		)
		(fp_line
			(start 0.4064 0.0889)
			(end 0.4064 1.6891)
			(stroke
				(width 0.1)
				(type default)
			)
			(layer "F.Fab")
		)
		(fp_line
			(start 0.4064 1.6891)
			(end -0.4064 1.6891)
			(stroke
				(width 0.1)
				(type default)
			)
			(layer "F.Fab")
		)
		(pad "1" smd rect
			(at 0 0)
			(size 0.762 1.27)
			(layers "F.Cu" "F.Mask" "F.Paste")
			(net "FM_RED_LED_ANODE")
		)
		(pad "2" smd rect
			(at 0 1.778)
			(size 0.762 1.27)
			(layers "F.Cu" "F.Mask" "F.Paste")
			(net "FM_RED_LED_CATHODE")
		)
		(zone
			(layer "F.Cu")
			(hatch none 0.5)
			(connect_pads
				(clearance 0)
			)
			(min_thickness 0.25)
			(keepout
				(tracks not_allowed)
				(vias allowed)
				(pads allowed)
				(copperpour not_allowed)
				(footprints allowed)
			)
			(placement
				(enabled no)
				(sheetname "")
			)
			(fill
				(thermal_gap 0.5)
				(thermal_bridge_width 0.5)
				(island_removal_mode 0)
			)
			(polygon
				(pts
					(xy 454.533 -28.6766) (xy 455.295 -28.6766) (xy 455.295 -28.2194) (xy 454.533 -28.2194)
				)
			)
		)
		(zone
			(layer "F.Cu")
			(hatch none 0.5)
			(connect_pads
				(clearance 0)
			)
			(min_thickness 0.25)
			(keepout
				(tracks allowed)
				(vias not_allowed)
				(pads allowed)
				(copperpour not_allowed)
				(footprints allowed)
			)
			(placement
				(enabled no)
				(sheetname "")
			)
			(fill
				(thermal_gap 0.5)
				(thermal_bridge_width 0.5)
				(island_removal_mode 0)
			)
			(polygon
				(pts
					(xy 454.533 -28.2194) (xy 455.295 -28.2194) (xy 455.295 -28.6766) (xy 454.533 -28.6766)
				)
			)
		)
	)
	(footprint ""
		(layer "F.Cu")
		(at 103.172768 -79.6036 180)
		(property "Reference" "C2D17"
			(at 0 0 180)
			(layer "F.SilkS")
			(hide yes)
			(effects
				(font
					(size 1.27 1.27)
				)
			)
		)
		(property "Value" ""
			(at 0 0 180)
			(layer "F.Fab")
			(effects
				(font
					(size 1.27 1.27)
				)
			)
		)
		(duplicate_pad_numbers_are_jumpers no)
		(fp_poly
			(pts
				(xy -0.4953 -0.2032) (xy 0.4953 -0.2032) (xy 0.4953 1.6002) (xy -0.4953 1.6002)
			)
			(stroke
				(width 0)
				(type default)
			)
			(fill no)
			(layer "F.CrtYd")
		)
		(fp_line
			(start 0.4953 1.6002)
			(end -0.4953 1.6002)
			(stroke
				(width 0.1)
				(type default)
			)
			(layer "F.Fab")
		)
		(fp_line
			(start 0.4953 -0.2032)
			(end 0.4953 1.6002)
			(stroke
				(width 0.1)
				(type default)
			)
			(layer "F.Fab")
		)
		(fp_line
			(start -0.4953 1.6002)
			(end -0.4953 -0.2032)
			(stroke
				(width 0.1)
				(type default)
			)
			(layer "F.Fab")
		)
		(fp_line
			(start -0.4953 -0.2032)
			(end 0.4953 -0.2032)
			(stroke
				(width 0.1)
				(type default)
			)
			(layer "F.Fab")
		)
		(pad "1" smd rect
			(at 0 0 180)
			(size 0.762 0.889)
			(layers "F.Cu" "F.Mask" "F.Paste")
			(net "PVCCIN_CPU1")
		)
		(pad "2" smd rect
			(at 0 1.397 180)
			(size 0.762 0.889)
			(layers "F.Cu" "F.Mask" "F.Paste")
			(net "GND")
		)
		(zone
			(layer "F.Cu")
			(hatch none 0.5)
			(connect_pads
				(clearance 0)
			)
			(min_thickness 0.25)
			(keepout
				(tracks not_allowed)
				(vias allowed)
				(pads allowed)
				(copperpour not_allowed)
				(footprints allowed)
			)
			(placement
				(enabled no)
				(sheetname "")
			)
			(fill
				(thermal_gap 0.5)
				(thermal_bridge_width 0.5)
				(island_removal_mode 0)
			)
			(polygon
				(pts
					(xy 103.553768 -80.0481) (xy 102.791768 -80.0481) (xy 102.791768 -80.5561) (xy 103.553768 -80.5561)
				)
			)
		)
	)
	(footprint ""
		(layer "F.Cu")
		(at 324.5485 -123.825 -90)
		(property "Reference" "C826"
			(at -0.8382 -0.67818 270)
			(unlocked yes)
			(layer "F.SilkS")
			(effects
				(font
					(size 0.4064 0.254)
					(thickness 0.1524)
				)
				(justify left)
			)
		)
		(property "Value" ""
			(at 0 0 270)
			(layer "F.Fab")
			(effects
				(font
					(size 1.27 1.27)
				)
			)
		)
		(duplicate_pad_numbers_are_jumpers no)
		(fp_poly
			(pts
				(xy 0.3048 -0.1016) (xy 0.3048 0.9906) (xy -0.3048 0.9906) (xy -0.3048 -0.1016)
			)
			(stroke
				(width 0)
				(type default)
			)
			(fill no)
			(layer "F.CrtYd")
		)
		(fp_line
			(start -0.3048 0.9906)
			(end 0.3048 0.9906)
			(stroke
				(width 0.1)
				(type default)
			)
			(layer "F.Fab")
		)
		(fp_line
			(start 0.3048 0.9906)
			(end 0.3048 -0.1016)
			(stroke
				(width 0.1)
				(type default)
			)
			(layer "F.Fab")
		)
		(fp_line
			(start -0.3048 -0.1016)
			(end -0.3048 0.9906)
			(stroke
				(width 0.1)
				(type default)
			)
			(layer "F.Fab")
		)
		(fp_line
			(start 0.3048 -0.1016)
			(end -0.3048 -0.1016)
			(stroke
				(width 0.1)
				(type default)
			)
			(layer "F.Fab")
		)
		(pad "1" smd rect
			(at 0 0 270)
			(size 0.508 0.508)
			(layers "F.Cu" "F.Mask" "F.Paste")
			(net "P3E_CPU0_PE1_PCH_TXN<14>")
		)
		(pad "2" smd rect
			(at 0 0.889 270)
			(size 0.508 0.508)
			(layers "F.Cu" "F.Mask" "F.Paste")
			(net "P3E_CPU0_PE1_PCH_CON_TXN<14>")
		)
		(zone
			(layer "F.Cu")
			(hatch none 0.5)
			(connect_pads
				(clearance 0)
			)
			(min_thickness 0.25)
			(keepout
				(tracks not_allowed)
				(vias allowed)
				(pads allowed)
				(copperpour not_allowed)
				(footprints allowed)
			)
			(placement
				(enabled no)
				(sheetname "")
			)
			(fill
				(thermal_gap 0.5)
				(thermal_bridge_width 0.5)
				(island_removal_mode 0)
			)
			(polygon
				(pts
					(xy 323.9135 -124.079) (xy 323.9135 -123.571) (xy 324.2945 -123.571) (xy 324.2945 -124.079)
				)
			)
		)
		(zone
			(layer "F.Cu")
			(hatch none 0.5)
			(connect_pads
				(clearance 0)
			)
			(min_thickness 0.25)
			(keepout
				(tracks allowed)
				(vias not_allowed)
				(pads allowed)
				(copperpour not_allowed)
				(footprints allowed)
			)
			(placement
				(enabled no)
				(sheetname "")
			)
			(fill
				(thermal_gap 0.5)
				(thermal_bridge_width 0.5)
				(island_removal_mode 0)
			)
			(polygon
				(pts
					(xy 324.2945 -124.079) (xy 324.2945 -123.571) (xy 323.9135 -123.571) (xy 323.9135 -124.079)
				)
			)
		)
	)
)
